(kicad_sch
	(version 20250114)
	(generator "eeschema")
	(generator_version "9.0")
	(paper "A3")
	(title_block
		(title "LPDDR4 testbed")
		(date "2024-03-26")
		(rev "1.2.2")
	)
	(text "IO_W4"
		(exclude_from_sim no)
		(at 271.78 114.3 0)
		(effects
			(font
				(size 1.27 1.27)
			)
			(justify left bottom)
		)
	)
	(text "IO_N5"
		(exclude_from_sim no)
		(at 271.78 142.24 0)
		(effects
			(font
				(size 1.27 1.27)
			)
			(justify left bottom)
		)
	)
	(text "IO_U5"
		(exclude_from_sim no)
		(at 271.78 124.46 0)
		(effects
			(font
				(size 1.27 1.27)
			)
			(justify left bottom)
		)
	)
	(text "IO_T4"
		(exclude_from_sim no)
		(at 271.78 127 0)
		(effects
			(font
				(size 1.27 1.27)
			)
			(justify left bottom)
		)
	)
	(text "test-board:IO_U12"
		(exclude_from_sim no)
		(at 80.645 224.155 0)
		(effects
			(font
				(size 1.27 1.27)
			)
			(justify left bottom)
		)
	)
	(text "VDDQ"
		(exclude_from_sim no)
		(at 288.29 212.09 0)
		(effects
			(font
				(size 2.0066 2.0066)
				(thickness 0.4013)
				(bold yes)
			)
			(justify left bottom)
		)
	)
	(text "IO_U3"
		(exclude_from_sim no)
		(at 271.78 121.92 0)
		(effects
			(font
				(size 1.27 1.27)
			)
			(justify left bottom)
		)
	)
	(text "IO_V4"
		(exclude_from_sim no)
		(at 271.78 119.38 0)
		(effects
			(font
				(size 1.27 1.27)
			)
			(justify left bottom)
		)
	)
	(text "IO_P4"
		(exclude_from_sim no)
		(at 271.78 134.62 0)
		(effects
			(font
				(size 1.27 1.27)
			)
			(justify left bottom)
		)
	)
	(text "test-board:IO_V12"
		(exclude_from_sim no)
		(at 80.645 226.695 0)
		(effects
			(font
				(size 1.27 1.27)
			)
			(justify left bottom)
		)
	)
	(text "SODIMM Connector"
		(exclude_from_sim no)
		(at 22.86 22.225 0)
		(effects
			(font
				(size 2.4892 2.4892)
				(thickness 0.4978)
				(bold yes)
			)
			(justify left bottom)
		)
	)
	(text "IO_V3"
		(exclude_from_sim no)
		(at 271.78 116.84 0)
		(effects
			(font
				(size 1.27 1.27)
			)
			(justify left bottom)
		)
	)
	(text "IO_R4"
		(exclude_from_sim no)
		(at 271.78 129.54 0)
		(effects
			(font
				(size 1.27 1.27)
			)
			(justify left bottom)
		)
	)
	(text "1V8_SYS"
		(exclude_from_sim no)
		(at 169.545 209.55 0)
		(effects
			(font
				(size 2.0066 2.0066)
				(thickness 0.4013)
				(bold yes)
			)
			(justify left bottom)
		)
	)
	(text "VDDQ"
		(exclude_from_sim no)
		(at 170.18 222.25 0)
		(effects
			(font
				(size 2.0066 2.0066)
				(thickness 0.4013)
				(bold yes)
			)
			(justify left bottom)
		)
	)
	(text "1V1_SYS"
		(exclude_from_sim no)
		(at 83.185 181.61 0)
		(effects
			(font
				(size 2.0066 2.0066)
				(thickness 0.4013)
				(bold yes)
			)
			(justify left bottom)
		)
	)
	(junction
		(at 117.475 106.68)
		(diameter 0)
		(color 0 0 0 0)
	)
	(junction
		(at 111.76 193.04)
		(diameter 0)
		(color 0 0 0 0)
	)
	(junction
		(at 117.475 81.28)
		(diameter 0)
		(color 0 0 0 0)
	)
	(junction
		(at 117.475 71.12)
		(diameter 0)
		(color 0 0 0 0)
	)
	(junction
		(at 117.475 119.38)
		(diameter 0)
		(color 0 0 0 0)
	)
	(junction
		(at 149.225 78.74)
		(diameter 0)
		(color 0 0 0 0)
	)
	(junction
		(at 117.475 88.9)
		(diameter 0)
		(color 0 0 0 0)
	)
	(junction
		(at 153.035 213.36)
		(diameter 0)
		(color 0 0 0 0)
	)
	(junction
		(at 117.475 93.98)
		(diameter 0)
		(color 0 0 0 0)
	)
	(junction
		(at 273.05 210.82)
		(diameter 0)
		(color 0 0 0 0)
	)
	(junction
		(at 159.385 208.28)
		(diameter 0)
		(color 0 0 0 0)
	)
	(junction
		(at 270.51 152.4)
		(diameter 0)
		(color 0 0 0 0)
	)
	(junction
		(at 117.475 96.52)
		(diameter 0)
		(color 0 0 0 0)
	)
	(junction
		(at 111.76 195.58)
		(diameter 0)
		(color 0 0 0 0)
	)
	(junction
		(at 117.475 73.66)
		(diameter 0)
		(color 0 0 0 0)
	)
	(junction
		(at 117.475 101.6)
		(diameter 0)
		(color 0 0 0 0)
	)
	(junction
		(at 117.475 76.2)
		(diameter 0)
		(color 0 0 0 0)
	)
	(junction
		(at 149.225 88.9)
		(diameter 0)
		(color 0 0 0 0)
	)
	(junction
		(at 117.475 78.74)
		(diameter 0)
		(color 0 0 0 0)
	)
	(junction
		(at 239.395 167.64)
		(diameter 0)
		(color 0 0 0 0)
	)
	(junction
		(at 270.51 165.1)
		(diameter 0)
		(color 0 0 0 0)
	)
	(junction
		(at 149.225 121.92)
		(diameter 0)
		(color 0 0 0 0)
	)
	(junction
		(at 111.76 180.34)
		(diameter 0)
		(color 0 0 0 0)
	)
	(junction
		(at 117.475 104.14)
		(diameter 0)
		(color 0 0 0 0)
	)
	(junction
		(at 149.225 66.04)
		(diameter 0)
		(color 0 0 0 0)
	)
	(junction
		(at 111.76 185.42)
		(diameter 0)
		(color 0 0 0 0)
	)
	(junction
		(at 149.225 99.06)
		(diameter 0)
		(color 0 0 0 0)
	)
	(junction
		(at 159.385 220.98)
		(diameter 0)
		(color 0 0 0 0)
	)
	(junction
		(at 117.475 114.3)
		(diameter 0)
		(color 0 0 0 0)
	)
	(junction
		(at 117.475 66.04)
		(diameter 0)
		(color 0 0 0 0)
	)
	(junction
		(at 111.76 187.96)
		(diameter 0)
		(color 0 0 0 0)
	)
	(junction
		(at 149.225 83.82)
		(diameter 0)
		(color 0 0 0 0)
	)
	(junction
		(at 149.225 106.68)
		(diameter 0)
		(color 0 0 0 0)
	)
	(junction
		(at 149.225 63.5)
		(diameter 0)
		(color 0 0 0 0)
	)
	(junction
		(at 117.475 121.92)
		(diameter 0)
		(color 0 0 0 0)
	)
	(junction
		(at 239.395 147.32)
		(diameter 0)
		(color 0 0 0 0)
	)
	(junction
		(at 149.225 68.58)
		(diameter 0)
		(color 0 0 0 0)
	)
	(junction
		(at 117.475 116.84)
		(diameter 0)
		(color 0 0 0 0)
	)
	(junction
		(at 149.225 71.12)
		(diameter 0)
		(color 0 0 0 0)
	)
	(junction
		(at 153.035 215.9)
		(diameter 0)
		(color 0 0 0 0)
	)
	(junction
		(at 117.475 99.06)
		(diameter 0)
		(color 0 0 0 0)
	)
	(junction
		(at 111.76 182.88)
		(diameter 0)
		(color 0 0 0 0)
	)
	(junction
		(at 149.225 114.3)
		(diameter 0)
		(color 0 0 0 0)
	)
	(junction
		(at 149.225 86.36)
		(diameter 0)
		(color 0 0 0 0)
	)
	(junction
		(at 153.035 208.28)
		(diameter 0)
		(color 0 0 0 0)
	)
	(junction
		(at 149.225 124.46)
		(diameter 0)
		(color 0 0 0 0)
	)
	(junction
		(at 149.225 116.84)
		(diameter 0)
		(color 0 0 0 0)
	)
	(junction
		(at 273.05 213.36)
		(diameter 0)
		(color 0 0 0 0)
	)
	(junction
		(at 149.225 93.98)
		(diameter 0)
		(color 0 0 0 0)
	)
	(junction
		(at 149.225 96.52)
		(diameter 0)
		(color 0 0 0 0)
	)
	(junction
		(at 149.225 111.76)
		(diameter 0)
		(color 0 0 0 0)
	)
	(junction
		(at 239.395 124.46)
		(diameter 0)
		(color 0 0 0 0)
	)
	(junction
		(at 149.225 119.38)
		(diameter 0)
		(color 0 0 0 0)
	)
	(junction
		(at 149.225 91.44)
		(diameter 0)
		(color 0 0 0 0)
	)
	(junction
		(at 153.035 223.52)
		(diameter 0)
		(color 0 0 0 0)
	)
	(junction
		(at 117.475 86.36)
		(diameter 0)
		(color 0 0 0 0)
	)
	(junction
		(at 117.475 91.44)
		(diameter 0)
		(color 0 0 0 0)
	)
	(junction
		(at 149.225 76.2)
		(diameter 0)
		(color 0 0 0 0)
	)
	(junction
		(at 153.035 210.82)
		(diameter 0)
		(color 0 0 0 0)
	)
	(junction
		(at 270.51 111.76)
		(diameter 0)
		(color 0 0 0 0)
	)
	(junction
		(at 270.51 132.08)
		(diameter 0)
		(color 0 0 0 0)
	)
	(junction
		(at 107.95 180.34)
		(diameter 0)
		(color 0 0 0 0)
	)
	(junction
		(at 149.225 81.28)
		(diameter 0)
		(color 0 0 0 0)
	)
	(junction
		(at 149.225 109.22)
		(diameter 0)
		(color 0 0 0 0)
	)
	(junction
		(at 149.225 104.14)
		(diameter 0)
		(color 0 0 0 0)
	)
	(junction
		(at 117.475 83.82)
		(diameter 0)
		(color 0 0 0 0)
	)
	(junction
		(at 111.76 190.5)
		(diameter 0)
		(color 0 0 0 0)
	)
	(junction
		(at 117.475 109.22)
		(diameter 0)
		(color 0 0 0 0)
	)
	(junction
		(at 117.475 111.76)
		(diameter 0)
		(color 0 0 0 0)
	)
	(junction
		(at 149.225 101.6)
		(diameter 0)
		(color 0 0 0 0)
	)
	(junction
		(at 149.225 73.66)
		(diameter 0)
		(color 0 0 0 0)
	)
	(junction
		(at 153.035 220.98)
		(diameter 0)
		(color 0 0 0 0)
	)
	(junction
		(at 117.475 124.46)
		(diameter 0)
		(color 0 0 0 0)
	)
	(junction
		(at 117.475 68.58)
		(diameter 0)
		(color 0 0 0 0)
	)
	(no_connect
		(at 144.78 147.32)
	)
	(no_connect
		(at 243.84 172.72)
	)
	(no_connect
		(at 266.7 114.3)
	)
	(no_connect
		(at 121.92 160.02)
	)
	(no_connect
		(at 266.7 81.28)
	)
	(no_connect
		(at 144.78 185.42)
	)
	(no_connect
		(at 266.7 68.58)
	)
	(no_connect
		(at 266.7 124.46)
	)
	(no_connect
		(at 144.78 195.58)
	)
	(no_connect
		(at 266.7 182.88)
	)
	(no_connect
		(at 243.84 86.36)
	)
	(no_connect
		(at 121.92 157.48)
	)
	(no_connect
		(at 266.7 71.12)
	)
	(no_connect
		(at 144.78 190.5)
	)
	(no_connect
		(at 243.84 66.04)
	)
	(no_connect
		(at 121.92 200.66)
	)
	(no_connect
		(at 243.84 228.6)
	)
	(no_connect
		(at 121.92 137.16)
	)
	(no_connect
		(at 243.84 68.58)
	)
	(no_connect
		(at 121.92 162.56)
	)
	(no_connect
		(at 243.84 175.26)
	)
	(no_connect
		(at 266.7 152.4)
	)
	(no_connect
		(at 144.78 157.48)
	)
	(no_connect
		(at 144.78 137.16)
	)
	(no_connect
		(at 266.7 218.44)
	)
	(no_connect
		(at 144.78 182.88)
	)
	(no_connect
		(at 243.84 91.44)
	)
	(no_connect
		(at 243.84 93.98)
	)
	(no_connect
		(at 144.78 172.72)
	)
	(no_connect
		(at 243.84 203.2)
	)
	(no_connect
		(at 144.78 144.78)
	)
	(no_connect
		(at 266.7 116.84)
	)
	(no_connect
		(at 121.92 147.32)
	)
	(no_connect
		(at 121.92 170.18)
	)
	(no_connect
		(at 144.78 149.86)
	)
	(no_connect
		(at 266.7 167.64)
	)
	(no_connect
		(at 266.7 228.6)
	)
	(no_connect
		(at 144.78 152.4)
	)
	(no_connect
		(at 121.92 167.64)
	)
	(no_connect
		(at 266.7 226.06)
	)
	(no_connect
		(at 266.7 76.2)
	)
	(no_connect
		(at 266.7 208.28)
	)
	(no_connect
		(at 144.78 203.2)
	)
	(no_connect
		(at 243.84 195.58)
	)
	(no_connect
		(at 243.84 205.74)
	)
	(no_connect
		(at 266.7 180.34)
	)
	(no_connect
		(at 121.92 218.44)
	)
	(no_connect
		(at 266.7 119.38)
	)
	(no_connect
		(at 266.7 193.04)
	)
	(no_connect
		(at 266.7 78.74)
	)
	(no_connect
		(at 243.84 190.5)
	)
	(no_connect
		(at 266.7 129.54)
	)
	(no_connect
		(at 266.7 198.12)
	)
	(no_connect
		(at 243.84 213.36)
	)
	(no_connect
		(at 121.92 220.98)
	)
	(no_connect
		(at 243.84 96.52)
	)
	(no_connect
		(at 266.7 121.92)
	)
	(no_connect
		(at 144.78 170.18)
	)
	(no_connect
		(at 121.92 132.08)
	)
	(no_connect
		(at 144.78 162.56)
	)
	(no_connect
		(at 144.78 177.8)
	)
	(no_connect
		(at 266.7 127)
	)
	(no_connect
		(at 266.7 83.82)
	)
	(no_connect
		(at 243.84 185.42)
	)
	(no_connect
		(at 243.84 76.2)
	)
	(no_connect
		(at 243.84 215.9)
	)
	(no_connect
		(at 243.84 88.9)
	)
	(no_connect
		(at 144.78 198.12)
	)
	(no_connect
		(at 266.7 170.18)
	)
	(no_connect
		(at 144.78 160.02)
	)
	(no_connect
		(at 121.92 203.2)
	)
	(no_connect
		(at 243.84 170.18)
	)
	(no_connect
		(at 144.78 127)
	)
	(no_connect
		(at 266.7 91.44)
	)
	(no_connect
		(at 266.7 88.9)
	)
	(no_connect
		(at 243.84 182.88)
	)
	(no_connect
		(at 144.78 193.04)
	)
	(no_connect
		(at 266.7 172.72)
	)
	(no_connect
		(at 243.84 226.06)
	)
	(no_connect
		(at 243.84 210.82)
	)
	(no_connect
		(at 266.7 149.86)
	)
	(no_connect
		(at 121.92 152.4)
	)
	(no_connect
		(at 121.92 142.24)
	)
	(no_connect
		(at 266.7 185.42)
	)
	(no_connect
		(at 144.78 205.74)
	)
	(no_connect
		(at 121.92 134.62)
	)
	(no_connect
		(at 266.7 139.7)
	)
	(no_connect
		(at 243.84 81.28)
	)
	(no_connect
		(at 144.78 129.54)
	)
	(no_connect
		(at 243.84 73.66)
	)
	(no_connect
		(at 144.78 165.1)
	)
	(no_connect
		(at 266.7 162.56)
	)
	(no_connect
		(at 121.92 144.78)
	)
	(no_connect
		(at 121.92 149.86)
	)
	(no_connect
		(at 121.92 177.8)
	)
	(no_connect
		(at 266.7 205.74)
	)
	(no_connect
		(at 144.78 142.24)
	)
	(no_connect
		(at 121.92 154.94)
	)
	(no_connect
		(at 266.7 86.36)
	)
	(no_connect
		(at 243.84 187.96)
	)
	(no_connect
		(at 144.78 154.94)
	)
	(no_connect
		(at 266.7 175.26)
	)
	(no_connect
		(at 121.92 215.9)
	)
	(no_connect
		(at 121.92 172.72)
	)
	(no_connect
		(at 121.92 165.1)
	)
	(no_connect
		(at 144.78 167.64)
	)
	(no_connect
		(at 243.84 200.66)
	)
	(no_connect
		(at 121.92 210.82)
	)
	(no_connect
		(at 266.7 203.2)
	)
	(no_connect
		(at 243.84 198.12)
	)
	(no_connect
		(at 266.7 187.96)
	)
	(no_connect
		(at 121.92 205.74)
	)
	(no_connect
		(at 121.92 175.26)
	)
	(no_connect
		(at 243.84 220.98)
	)
	(no_connect
		(at 266.7 195.58)
	)
	(no_connect
		(at 144.78 132.08)
	)
	(no_connect
		(at 243.84 193.04)
	)
	(no_connect
		(at 243.84 99.06)
	)
	(no_connect
		(at 243.84 177.8)
	)
	(no_connect
		(at 144.78 175.26)
	)
	(no_connect
		(at 121.92 208.28)
	)
	(no_connect
		(at 243.84 218.44)
	)
	(no_connect
		(at 266.7 177.8)
	)
	(no_connect
		(at 144.78 200.66)
	)
	(no_connect
		(at 266.7 73.66)
	)
	(no_connect
		(at 144.78 134.62)
	)
	(no_connect
		(at 266.7 200.66)
	)
	(no_connect
		(at 266.7 220.98)
	)
	(no_connect
		(at 266.7 190.5)
	)
	(no_connect
		(at 243.84 78.74)
	)
	(no_connect
		(at 266.7 137.16)
	)
	(no_connect
		(at 243.84 223.52)
	)
	(no_connect
		(at 144.78 187.96)
	)
	(no_connect
		(at 266.7 223.52)
	)
	(no_connect
		(at 266.7 154.94)
	)
	(no_connect
		(at 121.92 213.36)
	)
	(no_connect
		(at 121.92 139.7)
	)
	(no_connect
		(at 243.84 101.6)
	)
	(no_connect
		(at 144.78 180.34)
	)
	(no_connect
		(at 266.7 66.04)
	)
	(no_connect
		(at 121.92 127)
	)
	(no_connect
		(at 243.84 83.82)
	)
	(no_connect
		(at 243.84 180.34)
	)
	(no_connect
		(at 243.84 71.12)
	)
	(no_connect
		(at 121.92 129.54)
	)
	(no_connect
		(at 243.84 208.28)
	)
	(no_connect
		(at 144.78 139.7)
	)
	(wire
		(pts
			(xy 239.395 167.64) (xy 243.84 167.64)
		)
		(stroke
			(width 0)
			(type default)
		)
	)
	(wire
		(pts
			(xy 144.78 78.74) (xy 149.225 78.74)
		)
		(stroke
			(width 0)
			(type default)
		)
	)
	(wire
		(pts
			(xy 144.78 213.36) (xy 153.035 213.36)
		)
		(stroke
			(width 0)
			(type default)
		)
	)
	(wire
		(pts
			(xy 117.475 111.76) (xy 117.475 114.3)
		)
		(stroke
			(width 0)
			(type default)
		)
	)
	(wire
		(pts
			(xy 117.475 73.66) (xy 117.475 76.2)
		)
		(stroke
			(width 0)
			(type default)
		)
	)
	(wire
		(pts
			(xy 225.425 165.1) (xy 243.84 165.1)
		)
		(stroke
			(width 0)
			(type default)
		)
	)
	(wire
		(pts
			(xy 117.475 106.68) (xy 117.475 109.22)
		)
		(stroke
			(width 0)
			(type default)
		)
	)
	(wire
		(pts
			(xy 117.475 63.5) (xy 117.475 66.04)
		)
		(stroke
			(width 0)
			(type default)
		)
	)
	(wire
		(pts
			(xy 149.225 104.14) (xy 149.225 106.68)
		)
		(stroke
			(width 0)
			(type default)
		)
	)
	(wire
		(pts
			(xy 225.425 160.02) (xy 243.84 160.02)
		)
		(stroke
			(width 0)
			(type default)
		)
	)
	(wire
		(pts
			(xy 266.7 215.9) (xy 273.05 215.9)
		)
		(stroke
			(width 0)
			(type default)
		)
	)
	(wire
		(pts
			(xy 117.475 104.14) (xy 117.475 106.68)
		)
		(stroke
			(width 0)
			(type default)
		)
	)
	(wire
		(pts
			(xy 117.475 101.6) (xy 117.475 104.14)
		)
		(stroke
			(width 0)
			(type default)
		)
	)
	(wire
		(pts
			(xy 107.95 180.34) (xy 104.14 180.34)
		)
		(stroke
			(width 0)
			(type default)
		)
	)
	(wire
		(pts
			(xy 153.035 223.52) (xy 153.035 220.98)
		)
		(stroke
			(width 0)
			(type default)
		)
	)
	(wire
		(pts
			(xy 149.225 68.58) (xy 149.225 71.12)
		)
		(stroke
			(width 0)
			(type default)
		)
	)
	(wire
		(pts
			(xy 149.225 63.5) (xy 149.225 66.04)
		)
		(stroke
			(width 0)
			(type default)
		)
	)
	(wire
		(pts
			(xy 153.035 220.98) (xy 159.385 220.98)
		)
		(stroke
			(width 0)
			(type default)
		)
	)
	(wire
		(pts
			(xy 225.425 111.76) (xy 243.84 111.76)
		)
		(stroke
			(width 0)
			(type default)
		)
	)
	(wire
		(pts
			(xy 111.76 180.34) (xy 107.95 180.34)
		)
		(stroke
			(width 0)
			(type default)
		)
	)
	(wire
		(pts
			(xy 149.225 62.865) (xy 149.225 63.5)
		)
		(stroke
			(width 0)
			(type default)
		)
	)
	(wire
		(pts
			(xy 239.395 104.14) (xy 239.395 124.46)
		)
		(stroke
			(width 0)
			(type default)
		)
	)
	(wire
		(pts
			(xy 117.475 121.92) (xy 121.92 121.92)
		)
		(stroke
			(width 0)
			(type default)
		)
	)
	(wire
		(pts
			(xy 225.425 142.24) (xy 243.84 142.24)
		)
		(stroke
			(width 0)
			(type default)
		)
	)
	(wire
		(pts
			(xy 273.05 213.36) (xy 273.05 210.82)
		)
		(stroke
			(width 0)
			(type default)
		)
	)
	(wire
		(pts
			(xy 111.76 198.12) (xy 121.92 198.12)
		)
		(stroke
			(width 0)
			(type default)
		)
	)
	(wire
		(pts
			(xy 149.225 109.22) (xy 149.225 111.76)
		)
		(stroke
			(width 0)
			(type default)
		)
	)
	(wire
		(pts
			(xy 225.425 127) (xy 243.84 127)
		)
		(stroke
			(width 0)
			(type default)
		)
	)
	(wire
		(pts
			(xy 159.385 220.345) (xy 159.385 220.98)
		)
		(stroke
			(width 0)
			(type default)
		)
	)
	(wire
		(pts
			(xy 149.225 116.84) (xy 149.225 119.38)
		)
		(stroke
			(width 0)
			(type default)
		)
	)
	(wire
		(pts
			(xy 270.51 152.4) (xy 270.51 165.1)
		)
		(stroke
			(width 0)
			(type default)
		)
	)
	(wire
		(pts
			(xy 144.78 96.52) (xy 149.225 96.52)
		)
		(stroke
			(width 0)
			(type default)
		)
	)
	(wire
		(pts
			(xy 159.385 208.28) (xy 162.56 208.28)
		)
		(stroke
			(width 0)
			(type default)
		)
	)
	(wire
		(pts
			(xy 117.475 88.9) (xy 117.475 91.44)
		)
		(stroke
			(width 0)
			(type default)
		)
	)
	(wire
		(pts
			(xy 117.475 119.38) (xy 121.92 119.38)
		)
		(stroke
			(width 0)
			(type default)
		)
	)
	(wire
		(pts
			(xy 117.475 78.74) (xy 121.92 78.74)
		)
		(stroke
			(width 0)
			(type default)
		)
	)
	(wire
		(pts
			(xy 225.425 106.68) (xy 243.84 106.68)
		)
		(stroke
			(width 0)
			(type default)
		)
	)
	(wire
		(pts
			(xy 149.225 93.98) (xy 149.225 96.52)
		)
		(stroke
			(width 0)
			(type default)
		)
	)
	(wire
		(pts
			(xy 225.425 139.7) (xy 243.84 139.7)
		)
		(stroke
			(width 0)
			(type default)
		)
	)
	(wire
		(pts
			(xy 144.78 109.22) (xy 149.225 109.22)
		)
		(stroke
			(width 0)
			(type default)
		)
	)
	(wire
		(pts
			(xy 117.475 66.04) (xy 117.475 68.58)
		)
		(stroke
			(width 0)
			(type default)
		)
	)
	(wire
		(pts
			(xy 144.78 63.5) (xy 149.225 63.5)
		)
		(stroke
			(width 0)
			(type default)
		)
	)
	(wire
		(pts
			(xy 111.76 195.58) (xy 111.76 193.04)
		)
		(stroke
			(width 0)
			(type default)
		)
	)
	(wire
		(pts
			(xy 104.14 226.06) (xy 121.92 226.06)
		)
		(stroke
			(width 0)
			(type default)
		)
	)
	(wire
		(pts
			(xy 149.225 121.92) (xy 149.225 124.46)
		)
		(stroke
			(width 0)
			(type default)
		)
	)
	(wire
		(pts
			(xy 144.78 93.98) (xy 149.225 93.98)
		)
		(stroke
			(width 0)
			(type default)
		)
	)
	(wire
		(pts
			(xy 117.475 114.3) (xy 121.92 114.3)
		)
		(stroke
			(width 0)
			(type default)
		)
	)
	(wire
		(pts
			(xy 266.7 144.78) (xy 286.385 144.78)
		)
		(stroke
			(width 0)
			(type default)
		)
	)
	(wire
		(pts
			(xy 111.76 190.5) (xy 111.76 187.96)
		)
		(stroke
			(width 0)
			(type default)
		)
	)
	(wire
		(pts
			(xy 111.76 187.96) (xy 121.92 187.96)
		)
		(stroke
			(width 0)
			(type default)
		)
	)
	(wire
		(pts
			(xy 225.425 129.54) (xy 243.84 129.54)
		)
		(stroke
			(width 0)
			(type default)
		)
	)
	(wire
		(pts
			(xy 111.76 190.5) (xy 121.92 190.5)
		)
		(stroke
			(width 0)
			(type default)
		)
	)
	(wire
		(pts
			(xy 225.425 149.86) (xy 243.84 149.86)
		)
		(stroke
			(width 0)
			(type default)
		)
	)
	(wire
		(pts
			(xy 117.475 83.82) (xy 117.475 86.36)
		)
		(stroke
			(width 0)
			(type default)
		)
	)
	(wire
		(pts
			(xy 117.475 99.06) (xy 121.92 99.06)
		)
		(stroke
			(width 0)
			(type default)
		)
	)
	(wire
		(pts
			(xy 153.035 213.36) (xy 153.035 210.82)
		)
		(stroke
			(width 0)
			(type default)
		)
	)
	(wire
		(pts
			(xy 117.475 111.76) (xy 121.92 111.76)
		)
		(stroke
			(width 0)
			(type default)
		)
	)
	(wire
		(pts
			(xy 144.78 210.82) (xy 153.035 210.82)
		)
		(stroke
			(width 0)
			(type default)
		)
	)
	(wire
		(pts
			(xy 149.225 83.82) (xy 149.225 86.36)
		)
		(stroke
			(width 0)
			(type default)
		)
	)
	(wire
		(pts
			(xy 117.475 71.12) (xy 121.92 71.12)
		)
		(stroke
			(width 0)
			(type default)
		)
	)
	(wire
		(pts
			(xy 159.385 207.645) (xy 159.385 208.28)
		)
		(stroke
			(width 0)
			(type default)
		)
	)
	(wire
		(pts
			(xy 273.05 215.9) (xy 273.05 213.36)
		)
		(stroke
			(width 0)
			(type default)
		)
	)
	(wire
		(pts
			(xy 111.76 193.04) (xy 111.76 190.5)
		)
		(stroke
			(width 0)
			(type default)
		)
	)
	(wire
		(pts
			(xy 239.395 167.64) (xy 239.395 231.775)
		)
		(stroke
			(width 0)
			(type default)
		)
	)
	(wire
		(pts
			(xy 149.225 78.74) (xy 149.225 81.28)
		)
		(stroke
			(width 0)
			(type default)
		)
	)
	(wire
		(pts
			(xy 270.51 93.98) (xy 270.51 111.76)
		)
		(stroke
			(width 0)
			(type default)
		)
	)
	(wire
		(pts
			(xy 117.475 93.98) (xy 117.475 96.52)
		)
		(stroke
			(width 0)
			(type default)
		)
	)
	(wire
		(pts
			(xy 144.78 121.92) (xy 149.225 121.92)
		)
		(stroke
			(width 0)
			(type default)
		)
	)
	(wire
		(pts
			(xy 149.225 76.2) (xy 149.225 78.74)
		)
		(stroke
			(width 0)
			(type default)
		)
	)
	(wire
		(pts
			(xy 144.78 101.6) (xy 149.225 101.6)
		)
		(stroke
			(width 0)
			(type default)
		)
	)
	(wire
		(pts
			(xy 153.035 210.82) (xy 153.035 208.28)
		)
		(stroke
			(width 0)
			(type default)
		)
	)
	(wire
		(pts
			(xy 144.78 226.06) (xy 153.035 226.06)
		)
		(stroke
			(width 0)
			(type default)
		)
	)
	(wire
		(pts
			(xy 117.475 124.46) (xy 121.92 124.46)
		)
		(stroke
			(width 0)
			(type default)
		)
	)
	(wire
		(pts
			(xy 266.7 160.02) (xy 286.385 160.02)
		)
		(stroke
			(width 0)
			(type default)
		)
	)
	(wire
		(pts
			(xy 144.78 124.46) (xy 149.225 124.46)
		)
		(stroke
			(width 0)
			(type default)
		)
	)
	(wire
		(pts
			(xy 225.425 154.94) (xy 243.84 154.94)
		)
		(stroke
			(width 0)
			(type default)
		)
	)
	(wire
		(pts
			(xy 266.7 101.6) (xy 286.385 101.6)
		)
		(stroke
			(width 0)
			(type default)
		)
	)
	(wire
		(pts
			(xy 144.78 220.98) (xy 153.035 220.98)
		)
		(stroke
			(width 0)
			(type default)
		)
	)
	(wire
		(pts
			(xy 239.395 104.14) (xy 243.84 104.14)
		)
		(stroke
			(width 0)
			(type default)
		)
	)
	(wire
		(pts
			(xy 149.225 111.76) (xy 149.225 114.3)
		)
		(stroke
			(width 0)
			(type default)
		)
	)
	(wire
		(pts
			(xy 144.78 119.38) (xy 149.225 119.38)
		)
		(stroke
			(width 0)
			(type default)
		)
	)
	(wire
		(pts
			(xy 117.475 124.46) (xy 117.475 231.775)
		)
		(stroke
			(width 0)
			(type default)
		)
	)
	(wire
		(pts
			(xy 117.475 93.98) (xy 121.92 93.98)
		)
		(stroke
			(width 0)
			(type default)
		)
	)
	(wire
		(pts
			(xy 266.7 210.82) (xy 273.05 210.82)
		)
		(stroke
			(width 0)
			(type default)
		)
	)
	(wire
		(pts
			(xy 149.225 106.68) (xy 149.225 109.22)
		)
		(stroke
			(width 0)
			(type default)
		)
	)
	(wire
		(pts
			(xy 149.225 96.52) (xy 149.225 99.06)
		)
		(stroke
			(width 0)
			(type default)
		)
	)
	(wire
		(pts
			(xy 111.76 180.34) (xy 121.92 180.34)
		)
		(stroke
			(width 0)
			(type default)
		)
	)
	(wire
		(pts
			(xy 117.475 121.92) (xy 117.475 124.46)
		)
		(stroke
			(width 0)
			(type default)
		)
	)
	(wire
		(pts
			(xy 266.7 96.52) (xy 286.385 96.52)
		)
		(stroke
			(width 0)
			(type default)
		)
	)
	(wire
		(pts
			(xy 111.76 195.58) (xy 121.92 195.58)
		)
		(stroke
			(width 0)
			(type default)
		)
	)
	(wire
		(pts
			(xy 273.05 210.82) (xy 279.4 210.82)
		)
		(stroke
			(width 0)
			(type default)
		)
	)
	(wire
		(pts
			(xy 117.475 91.44) (xy 121.92 91.44)
		)
		(stroke
			(width 0)
			(type default)
		)
	)
	(wire
		(pts
			(xy 111.76 182.88) (xy 121.92 182.88)
		)
		(stroke
			(width 0)
			(type default)
		)
	)
	(wire
		(pts
			(xy 266.7 109.22) (xy 286.385 109.22)
		)
		(stroke
			(width 0)
			(type default)
		)
	)
	(wire
		(pts
			(xy 239.395 147.32) (xy 243.84 147.32)
		)
		(stroke
			(width 0)
			(type default)
		)
	)
	(wire
		(pts
			(xy 117.475 68.58) (xy 121.92 68.58)
		)
		(stroke
			(width 0)
			(type default)
		)
	)
	(wire
		(pts
			(xy 239.395 124.46) (xy 243.84 124.46)
		)
		(stroke
			(width 0)
			(type default)
		)
	)
	(wire
		(pts
			(xy 144.78 114.3) (xy 149.225 114.3)
		)
		(stroke
			(width 0)
			(type default)
		)
	)
	(wire
		(pts
			(xy 149.225 99.06) (xy 149.225 101.6)
		)
		(stroke
			(width 0)
			(type default)
		)
	)
	(wire
		(pts
			(xy 117.475 76.2) (xy 117.475 78.74)
		)
		(stroke
			(width 0)
			(type default)
		)
	)
	(wire
		(pts
			(xy 153.035 226.06) (xy 153.035 223.52)
		)
		(stroke
			(width 0)
			(type default)
		)
	)
	(wire
		(pts
			(xy 153.035 208.28) (xy 159.385 208.28)
		)
		(stroke
			(width 0)
			(type default)
		)
	)
	(wire
		(pts
			(xy 144.78 215.9) (xy 153.035 215.9)
		)
		(stroke
			(width 0)
			(type default)
		)
	)
	(wire
		(pts
			(xy 144.78 91.44) (xy 149.225 91.44)
		)
		(stroke
			(width 0)
			(type default)
		)
	)
	(wire
		(pts
			(xy 111.76 185.42) (xy 111.76 182.88)
		)
		(stroke
			(width 0)
			(type default)
		)
	)
	(wire
		(pts
			(xy 144.78 73.66) (xy 149.225 73.66)
		)
		(stroke
			(width 0)
			(type default)
		)
	)
	(wire
		(pts
			(xy 266.7 157.48) (xy 286.385 157.48)
		)
		(stroke
			(width 0)
			(type default)
		)
	)
	(wire
		(pts
			(xy 225.425 152.4) (xy 243.84 152.4)
		)
		(stroke
			(width 0)
			(type default)
		)
	)
	(wire
		(pts
			(xy 117.475 66.04) (xy 121.92 66.04)
		)
		(stroke
			(width 0)
			(type default)
		)
	)
	(wire
		(pts
			(xy 144.78 66.04) (xy 149.225 66.04)
		)
		(stroke
			(width 0)
			(type default)
		)
	)
	(wire
		(pts
			(xy 117.475 96.52) (xy 117.475 99.06)
		)
		(stroke
			(width 0)
			(type default)
		)
	)
	(wire
		(pts
			(xy 144.78 104.14) (xy 149.225 104.14)
		)
		(stroke
			(width 0)
			(type default)
		)
	)
	(wire
		(pts
			(xy 144.78 83.82) (xy 149.225 83.82)
		)
		(stroke
			(width 0)
			(type default)
		)
	)
	(wire
		(pts
			(xy 117.475 73.66) (xy 121.92 73.66)
		)
		(stroke
			(width 0)
			(type default)
		)
	)
	(wire
		(pts
			(xy 149.225 71.12) (xy 149.225 73.66)
		)
		(stroke
			(width 0)
			(type default)
		)
	)
	(wire
		(pts
			(xy 111.76 187.96) (xy 111.76 185.42)
		)
		(stroke
			(width 0)
			(type default)
		)
	)
	(wire
		(pts
			(xy 117.475 114.3) (xy 117.475 116.84)
		)
		(stroke
			(width 0)
			(type default)
		)
	)
	(wire
		(pts
			(xy 225.425 157.48) (xy 243.84 157.48)
		)
		(stroke
			(width 0)
			(type default)
		)
	)
	(wire
		(pts
			(xy 149.225 88.9) (xy 149.225 91.44)
		)
		(stroke
			(width 0)
			(type default)
		)
	)
	(wire
		(pts
			(xy 270.51 132.08) (xy 270.51 152.4)
		)
		(stroke
			(width 0)
			(type default)
		)
	)
	(wire
		(pts
			(xy 144.78 218.44) (xy 153.035 218.44)
		)
		(stroke
			(width 0)
			(type default)
		)
	)
	(wire
		(pts
			(xy 149.225 91.44) (xy 149.225 93.98)
		)
		(stroke
			(width 0)
			(type default)
		)
	)
	(wire
		(pts
			(xy 270.51 165.1) (xy 270.51 231.775)
		)
		(stroke
			(width 0)
			(type default)
		)
	)
	(wire
		(pts
			(xy 117.475 63.5) (xy 121.92 63.5)
		)
		(stroke
			(width 0)
			(type default)
		)
	)
	(wire
		(pts
			(xy 144.78 99.06) (xy 149.225 99.06)
		)
		(stroke
			(width 0)
			(type default)
		)
	)
	(wire
		(pts
			(xy 117.475 96.52) (xy 121.92 96.52)
		)
		(stroke
			(width 0)
			(type default)
		)
	)
	(wire
		(pts
			(xy 225.425 144.78) (xy 243.84 144.78)
		)
		(stroke
			(width 0)
			(type default)
		)
	)
	(wire
		(pts
			(xy 149.225 114.3) (xy 149.225 116.84)
		)
		(stroke
			(width 0)
			(type default)
		)
	)
	(wire
		(pts
			(xy 144.78 86.36) (xy 149.225 86.36)
		)
		(stroke
			(width 0)
			(type default)
		)
	)
	(wire
		(pts
			(xy 149.225 81.28) (xy 149.225 83.82)
		)
		(stroke
			(width 0)
			(type default)
		)
	)
	(wire
		(pts
			(xy 111.76 198.12) (xy 111.76 195.58)
		)
		(stroke
			(width 0)
			(type default)
		)
	)
	(wire
		(pts
			(xy 117.475 119.38) (xy 117.475 121.92)
		)
		(stroke
			(width 0)
			(type default)
		)
	)
	(wire
		(pts
			(xy 117.475 116.84) (xy 121.92 116.84)
		)
		(stroke
			(width 0)
			(type default)
		)
	)
	(wire
		(pts
			(xy 144.78 68.58) (xy 149.225 68.58)
		)
		(stroke
			(width 0)
			(type default)
		)
	)
	(wire
		(pts
			(xy 225.425 134.62) (xy 243.84 134.62)
		)
		(stroke
			(width 0)
			(type default)
		)
	)
	(wire
		(pts
			(xy 104.14 223.52) (xy 121.92 223.52)
		)
		(stroke
			(width 0)
			(type default)
		)
	)
	(wire
		(pts
			(xy 117.475 86.36) (xy 117.475 88.9)
		)
		(stroke
			(width 0)
			(type default)
		)
	)
	(wire
		(pts
			(xy 266.7 99.06) (xy 286.385 99.06)
		)
		(stroke
			(width 0)
			(type default)
		)
	)
	(wire
		(pts
			(xy 266.7 111.76) (xy 270.51 111.76)
		)
		(stroke
			(width 0)
			(type default)
		)
	)
	(wire
		(pts
			(xy 117.475 86.36) (xy 121.92 86.36)
		)
		(stroke
			(width 0)
			(type default)
		)
	)
	(wire
		(pts
			(xy 144.78 76.2) (xy 149.225 76.2)
		)
		(stroke
			(width 0)
			(type default)
		)
	)
	(wire
		(pts
			(xy 111.76 185.42) (xy 121.92 185.42)
		)
		(stroke
			(width 0)
			(type default)
		)
	)
	(wire
		(pts
			(xy 117.475 91.44) (xy 117.475 93.98)
		)
		(stroke
			(width 0)
			(type default)
		)
	)
	(wire
		(pts
			(xy 144.78 71.12) (xy 149.225 71.12)
		)
		(stroke
			(width 0)
			(type default)
		)
	)
	(wire
		(pts
			(xy 117.475 81.28) (xy 121.92 81.28)
		)
		(stroke
			(width 0)
			(type default)
		)
	)
	(wire
		(pts
			(xy 266.7 213.36) (xy 273.05 213.36)
		)
		(stroke
			(width 0)
			(type default)
		)
	)
	(wire
		(pts
			(xy 117.475 109.22) (xy 117.475 111.76)
		)
		(stroke
			(width 0)
			(type default)
		)
	)
	(wire
		(pts
			(xy 149.225 124.46) (xy 149.225 231.775)
		)
		(stroke
			(width 0)
			(type default)
		)
	)
	(wire
		(pts
			(xy 266.7 147.32) (xy 286.385 147.32)
		)
		(stroke
			(width 0)
			(type default)
		)
	)
	(wire
		(pts
			(xy 144.78 223.52) (xy 153.035 223.52)
		)
		(stroke
			(width 0)
			(type default)
		)
	)
	(wire
		(pts
			(xy 107.95 179.705) (xy 107.95 180.34)
		)
		(stroke
			(width 0)
			(type default)
		)
	)
	(wire
		(pts
			(xy 266.7 132.08) (xy 270.51 132.08)
		)
		(stroke
			(width 0)
			(type default)
		)
	)
	(wire
		(pts
			(xy 239.395 124.46) (xy 239.395 147.32)
		)
		(stroke
			(width 0)
			(type default)
		)
	)
	(wire
		(pts
			(xy 111.76 182.88) (xy 111.76 180.34)
		)
		(stroke
			(width 0)
			(type default)
		)
	)
	(wire
		(pts
			(xy 266.7 152.4) (xy 270.51 152.4)
		)
		(stroke
			(width 0)
			(type default)
		)
	)
	(wire
		(pts
			(xy 117.475 88.9) (xy 121.92 88.9)
		)
		(stroke
			(width 0)
			(type default)
		)
	)
	(wire
		(pts
			(xy 144.78 116.84) (xy 149.225 116.84)
		)
		(stroke
			(width 0)
			(type default)
		)
	)
	(wire
		(pts
			(xy 225.425 119.38) (xy 243.84 119.38)
		)
		(stroke
			(width 0)
			(type default)
		)
	)
	(wire
		(pts
			(xy 117.475 106.68) (xy 121.92 106.68)
		)
		(stroke
			(width 0)
			(type default)
		)
	)
	(wire
		(pts
			(xy 270.51 111.76) (xy 270.51 132.08)
		)
		(stroke
			(width 0)
			(type default)
		)
	)
	(wire
		(pts
			(xy 117.475 116.84) (xy 117.475 119.38)
		)
		(stroke
			(width 0)
			(type default)
		)
	)
	(wire
		(pts
			(xy 117.475 68.58) (xy 117.475 71.12)
		)
		(stroke
			(width 0)
			(type default)
		)
	)
	(wire
		(pts
			(xy 266.7 93.98) (xy 270.51 93.98)
		)
		(stroke
			(width 0)
			(type default)
		)
	)
	(wire
		(pts
			(xy 117.475 104.14) (xy 121.92 104.14)
		)
		(stroke
			(width 0)
			(type default)
		)
	)
	(wire
		(pts
			(xy 117.475 109.22) (xy 121.92 109.22)
		)
		(stroke
			(width 0)
			(type default)
		)
	)
	(wire
		(pts
			(xy 225.425 109.22) (xy 243.84 109.22)
		)
		(stroke
			(width 0)
			(type default)
		)
	)
	(wire
		(pts
			(xy 111.76 193.04) (xy 121.92 193.04)
		)
		(stroke
			(width 0)
			(type default)
		)
	)
	(wire
		(pts
			(xy 144.78 106.68) (xy 149.225 106.68)
		)
		(stroke
			(width 0)
			(type default)
		)
	)
	(wire
		(pts
			(xy 266.7 104.14) (xy 286.385 104.14)
		)
		(stroke
			(width 0)
			(type default)
		)
	)
	(wire
		(pts
			(xy 225.425 121.92) (xy 243.84 121.92)
		)
		(stroke
			(width 0)
			(type default)
		)
	)
	(wire
		(pts
			(xy 117.475 99.06) (xy 117.475 101.6)
		)
		(stroke
			(width 0)
			(type default)
		)
	)
	(wire
		(pts
			(xy 117.475 71.12) (xy 117.475 73.66)
		)
		(stroke
			(width 0)
			(type default)
		)
	)
	(wire
		(pts
			(xy 239.395 147.32) (xy 239.395 167.64)
		)
		(stroke
			(width 0)
			(type default)
		)
	)
	(wire
		(pts
			(xy 159.385 220.98) (xy 162.56 220.98)
		)
		(stroke
			(width 0)
			(type default)
		)
	)
	(wire
		(pts
			(xy 225.425 162.56) (xy 243.84 162.56)
		)
		(stroke
			(width 0)
			(type default)
		)
	)
	(wire
		(pts
			(xy 153.035 218.44) (xy 153.035 215.9)
		)
		(stroke
			(width 0)
			(type default)
		)
	)
	(wire
		(pts
			(xy 144.78 81.28) (xy 149.225 81.28)
		)
		(stroke
			(width 0)
			(type default)
		)
	)
	(wire
		(pts
			(xy 117.475 83.82) (xy 121.92 83.82)
		)
		(stroke
			(width 0)
			(type default)
		)
	)
	(wire
		(pts
			(xy 144.78 111.76) (xy 149.225 111.76)
		)
		(stroke
			(width 0)
			(type default)
		)
	)
	(wire
		(pts
			(xy 266.7 165.1) (xy 270.51 165.1)
		)
		(stroke
			(width 0)
			(type default)
		)
	)
	(wire
		(pts
			(xy 149.225 119.38) (xy 149.225 121.92)
		)
		(stroke
			(width 0)
			(type default)
		)
	)
	(wire
		(pts
			(xy 149.225 86.36) (xy 149.225 88.9)
		)
		(stroke
			(width 0)
			(type default)
		)
	)
	(wire
		(pts
			(xy 149.225 66.04) (xy 149.225 68.58)
		)
		(stroke
			(width 0)
			(type default)
		)
	)
	(wire
		(pts
			(xy 149.225 73.66) (xy 149.225 76.2)
		)
		(stroke
			(width 0)
			(type default)
		)
	)
	(wire
		(pts
			(xy 117.475 76.2) (xy 121.92 76.2)
		)
		(stroke
			(width 0)
			(type default)
		)
	)
	(wire
		(pts
			(xy 117.475 78.74) (xy 117.475 81.28)
		)
		(stroke
			(width 0)
			(type default)
		)
	)
	(wire
		(pts
			(xy 117.475 81.28) (xy 117.475 83.82)
		)
		(stroke
			(width 0)
			(type default)
		)
	)
	(wire
		(pts
			(xy 225.425 137.16) (xy 243.84 137.16)
		)
		(stroke
			(width 0)
			(type default)
		)
	)
	(wire
		(pts
			(xy 225.425 116.84) (xy 243.84 116.84)
		)
		(stroke
			(width 0)
			(type default)
		)
	)
	(wire
		(pts
			(xy 117.475 101.6) (xy 121.92 101.6)
		)
		(stroke
			(width 0)
			(type default)
		)
	)
	(wire
		(pts
			(xy 266.7 142.24) (xy 286.385 142.24)
		)
		(stroke
			(width 0)
			(type default)
		)
	)
	(wire
		(pts
			(xy 144.78 88.9) (xy 149.225 88.9)
		)
		(stroke
			(width 0)
			(type default)
		)
	)
	(wire
		(pts
			(xy 149.225 101.6) (xy 149.225 104.14)
		)
		(stroke
			(width 0)
			(type default)
		)
	)
	(wire
		(pts
			(xy 266.7 134.62) (xy 286.385 134.62)
		)
		(stroke
			(width 0)
			(type default)
		)
	)
	(wire
		(pts
			(xy 266.7 106.68) (xy 286.385 106.68)
		)
		(stroke
			(width 0)
			(type default)
		)
	)
	(wire
		(pts
			(xy 144.78 208.28) (xy 153.035 208.28)
		)
		(stroke
			(width 0)
			(type default)
		)
	)
	(wire
		(pts
			(xy 225.425 132.08) (xy 243.84 132.08)
		)
		(stroke
			(width 0)
			(type default)
		)
	)
	(wire
		(pts
			(xy 225.425 114.3) (xy 243.84 114.3)
		)
		(stroke
			(width 0)
			(type default)
		)
	)
	(wire
		(pts
			(xy 153.035 215.9) (xy 153.035 213.36)
		)
		(stroke
			(width 0)
			(type default)
		)
	)
	(global_label "VDDQ"
		(shape input)
		(at 162.56 220.98 0)
		(fields_autoplaced yes)
		(effects
			(font
				(size 1.27 1.27)
			)
			(justify left)
		)
		(property "Intersheetrefs" "${INTERSHEET_REFS}"
			(at 5.08 0 0)
			(effects
				(font
					(size 1.27 1.27)
				)
				(hide yes)
			)
		)
	)
	(global_label "VDD2"
		(shape input)
		(at 104.14 180.34 180)
		(fields_autoplaced yes)
		(effects
			(font
				(size 1.27 1.27)
			)
			(justify right)
		)
		(property "Intersheetrefs" "${INTERSHEET_REFS}"
			(at 0.635 0 0)
			(effects
				(font
					(size 1.27 1.27)
				)
				(hide yes)
			)
		)
	)
	(global_label "DQ03_A"
		(shape input)
		(at 225.425 165.1 180)
		(fields_autoplaced yes)
		(effects
			(font
				(size 1.27 1.27)
			)
			(justify right)
		)
		(property "Intersheetrefs" "${INTERSHEET_REFS}"
			(at 216.0183 165.1 0)
			(effects
				(font
					(size 1.27 1.27)
				)
				(justify right)
				(hide yes)
			)
		)
	)
	(global_label "CA0_A"
		(shape input)
		(at 286.385 157.48 0)
		(fields_autoplaced yes)
		(effects
			(font
				(size 1.27 1.27)
			)
			(justify left)
		)
		(property "Intersheetrefs" "${INTERSHEET_REFS}"
			(at 294.3335 157.4006 0)
			(effects
				(font
					(size 1.27 1.27)
				)
				(justify left)
				(hide yes)
			)
		)
	)
	(global_label "DQ08_A"
		(shape input)
		(at 225.425 114.3 180)
		(fields_autoplaced yes)
		(effects
			(font
				(size 1.27 1.27)
			)
			(justify right)
		)
		(property "Intersheetrefs" "${INTERSHEET_REFS}"
			(at 216.0183 114.3 0)
			(effects
				(font
					(size 1.27 1.27)
				)
				(justify right)
				(hide yes)
			)
		)
	)
	(global_label "DQ11_A"
		(shape input)
		(at 225.425 106.68 180)
		(fields_autoplaced yes)
		(effects
			(font
				(size 1.27 1.27)
			)
			(justify right)
		)
		(property "Intersheetrefs" "${INTERSHEET_REFS}"
			(at 216.0183 106.68 0)
			(effects
				(font
					(size 1.27 1.27)
				)
				(justify right)
				(hide yes)
			)
		)
	)
	(global_label "DQ_S0_CA"
		(shape input)
		(at 225.425 152.4 180)
		(fields_autoplaced yes)
		(effects
			(font
				(size 1.27 1.27)
			)
			(justify right)
		)
		(property "Intersheetrefs" "${INTERSHEET_REFS}"
			(at 213.7807 152.4 0)
			(effects
				(font
					(size 1.27 1.27)
				)
				(justify right)
				(hide yes)
			)
		)
	)
	(global_label "DQ_S1_CA"
		(shape input)
		(at 225.425 119.38 180)
		(fields_autoplaced yes)
		(effects
			(font
				(size 1.27 1.27)
			)
			(justify right)
		)
		(property "Intersheetrefs" "${INTERSHEET_REFS}"
			(at 213.7807 119.38 0)
			(effects
				(font
					(size 1.27 1.27)
				)
				(justify right)
				(hide yes)
			)
		)
	)
	(global_label "CA4_A"
		(shape input)
		(at 286.385 99.06 0)
		(fields_autoplaced yes)
		(effects
			(font
				(size 1.27 1.27)
			)
			(justify left)
		)
		(property "Intersheetrefs" "${INTERSHEET_REFS}"
			(at 2.54 0 0)
			(effects
				(font
					(size 1.27 1.27)
				)
				(hide yes)
			)
		)
	)
	(global_label "CA1_A"
		(shape input)
		(at 286.385 160.02 0)
		(fields_autoplaced yes)
		(effects
			(font
				(size 1.27 1.27)
			)
			(justify left)
		)
		(property "Intersheetrefs" "${INTERSHEET_REFS}"
			(at 294.3335 159.9406 0)
			(effects
				(font
					(size 1.27 1.27)
				)
				(justify left)
				(hide yes)
			)
		)
	)
	(global_label "DQ01_A"
		(shape input)
		(at 225.425 160.02 180)
		(fields_autoplaced yes)
		(effects
			(font
				(size 1.27 1.27)
			)
			(justify right)
		)
		(property "Intersheetrefs" "${INTERSHEET_REFS}"
			(at 216.0183 160.02 0)
			(effects
				(font
					(size 1.27 1.27)
				)
				(justify right)
				(hide yes)
			)
		)
	)
	(global_label "DMI_0A"
		(shape input)
		(at 225.425 149.86 180)
		(fields_autoplaced yes)
		(effects
			(font
				(size 1.27 1.27)
			)
			(justify right)
		)
		(property "Intersheetrefs" "${INTERSHEET_REFS}"
			(at 216.5021 149.86 0)
			(effects
				(font
					(size 1.27 1.27)
				)
				(justify right)
				(hide yes)
			)
		)
	)
	(global_label "DQ14_A"
		(shape input)
		(at 225.425 129.54 180)
		(fields_autoplaced yes)
		(effects
			(font
				(size 1.27 1.27)
			)
			(justify right)
		)
		(property "Intersheetrefs" "${INTERSHEET_REFS}"
			(at 216.0183 129.54 0)
			(effects
				(font
					(size 1.27 1.27)
				)
				(justify right)
				(hide yes)
			)
		)
	)
	(global_label "SDA"
		(shape input)
		(at 104.14 223.52 180)
		(fields_autoplaced yes)
		(effects
			(font
				(size 1.27 1.27)
			)
			(justify right)
		)
		(property "Intersheetrefs" "${INTERSHEET_REFS}"
			(at 0.635 0 0)
			(effects
				(font
					(size 1.27 1.27)
				)
				(hide yes)
			)
		)
	)
	(global_label "DQ09_A"
		(shape input)
		(at 225.425 111.76 180)
		(fields_autoplaced yes)
		(effects
			(font
				(size 1.27 1.27)
			)
			(justify right)
		)
		(property "Intersheetrefs" "${INTERSHEET_REFS}"
			(at 216.0183 111.76 0)
			(effects
				(font
					(size 1.27 1.27)
				)
				(justify right)
				(hide yes)
			)
		)
	)
	(global_label "DQ13_A"
		(shape input)
		(at 225.425 132.08 180)
		(fields_autoplaced yes)
		(effects
			(font
				(size 1.27 1.27)
			)
			(justify right)
		)
		(property "Intersheetrefs" "${INTERSHEET_REFS}"
			(at 216.0183 132.08 0)
			(effects
				(font
					(size 1.27 1.27)
				)
				(justify right)
				(hide yes)
			)
		)
	)
	(global_label "RESET_N"
		(shape input)
		(at 286.385 134.62 0)
		(fields_autoplaced yes)
		(effects
			(font
				(size 1.27 1.27)
			)
			(justify left)
		)
		(property "Intersheetrefs" "${INTERSHEET_REFS}"
			(at 2.54 0 0)
			(effects
				(font
					(size 1.27 1.27)
				)
				(hide yes)
			)
		)
	)
	(global_label "CA3_A"
		(shape input)
		(at 286.385 101.6 0)
		(fields_autoplaced yes)
		(effects
			(font
				(size 1.27 1.27)
			)
			(justify left)
		)
		(property "Intersheetrefs" "${INTERSHEET_REFS}"
			(at 2.54 0 0)
			(effects
				(font
					(size 1.27 1.27)
				)
				(hide yes)
			)
		)
	)
	(global_label "DQ02_A"
		(shape input)
		(at 225.425 162.56 180)
		(fields_autoplaced yes)
		(effects
			(font
				(size 1.27 1.27)
			)
			(justify right)
		)
		(property "Intersheetrefs" "${INTERSHEET_REFS}"
			(at 216.0183 162.56 0)
			(effects
				(font
					(size 1.27 1.27)
				)
				(justify right)
				(hide yes)
			)
		)
	)
	(global_label "DQ04_A"
		(shape input)
		(at 225.425 137.16 180)
		(fields_autoplaced yes)
		(effects
			(font
				(size 1.27 1.27)
			)
			(justify right)
		)
		(property "Intersheetrefs" "${INTERSHEET_REFS}"
			(at 216.0183 137.16 0)
			(effects
				(font
					(size 1.27 1.27)
				)
				(justify right)
				(hide yes)
			)
		)
	)
	(global_label "CK_C_A"
		(shape input)
		(at 286.385 106.68 0)
		(fields_autoplaced yes)
		(effects
			(font
				(size 1.27 1.27)
			)
			(justify left)
		)
		(property "Intersheetrefs" "${INTERSHEET_REFS}"
			(at 295.543 106.7594 0)
			(effects
				(font
					(size 1.27 1.27)
				)
				(justify left)
				(hide yes)
			)
		)
	)
	(global_label "CA5_A"
		(shape input)
		(at 286.385 96.52 0)
		(fields_autoplaced yes)
		(effects
			(font
				(size 1.27 1.27)
			)
			(justify left)
		)
		(property "Intersheetrefs" "${INTERSHEET_REFS}"
			(at 2.54 0 0)
			(effects
				(font
					(size 1.27 1.27)
				)
				(hide yes)
			)
		)
	)
	(global_label "CS0_A"
		(shape input)
		(at 286.385 144.78 0)
		(fields_autoplaced yes)
		(effects
			(font
				(size 1.27 1.27)
			)
			(justify left)
		)
		(property "Intersheetrefs" "${INTERSHEET_REFS}"
			(at 2.54 0 0)
			(effects
				(font
					(size 1.27 1.27)
				)
				(hide yes)
			)
		)
	)
	(global_label "DQ00_A"
		(shape input)
		(at 225.425 157.48 180)
		(fields_autoplaced yes)
		(effects
			(font
				(size 1.27 1.27)
			)
			(justify right)
		)
		(property "Intersheetrefs" "${INTERSHEET_REFS}"
			(at 216.0183 157.48 0)
			(effects
				(font
					(size 1.27 1.27)
				)
				(justify right)
				(hide yes)
			)
		)
	)
	(global_label "DQ07_A"
		(shape input)
		(at 225.425 144.78 180)
		(fields_autoplaced yes)
		(effects
			(font
				(size 1.27 1.27)
			)
			(justify right)
		)
		(property "Intersheetrefs" "${INTERSHEET_REFS}"
			(at 216.0183 144.78 0)
			(effects
				(font
					(size 1.27 1.27)
				)
				(justify right)
				(hide yes)
			)
		)
	)
	(global_label "DQ06_A"
		(shape input)
		(at 225.425 142.24 180)
		(fields_autoplaced yes)
		(effects
			(font
				(size 1.27 1.27)
			)
			(justify right)
		)
		(property "Intersheetrefs" "${INTERSHEET_REFS}"
			(at 216.0183 142.24 0)
			(effects
				(font
					(size 1.27 1.27)
				)
				(justify right)
				(hide yes)
			)
		)
	)
	(global_label "SCL"
		(shape input)
		(at 104.14 226.06 180)
		(fields_autoplaced yes)
		(effects
			(font
				(size 1.27 1.27)
			)
			(justify right)
		)
		(property "Intersheetrefs" "${INTERSHEET_REFS}"
			(at 0.635 0 0)
			(effects
				(font
					(size 1.27 1.27)
				)
				(hide yes)
			)
		)
	)
	(global_label "CK_T_A"
		(shape input)
		(at 286.385 109.22 0)
		(fields_autoplaced yes)
		(effects
			(font
				(size 1.27 1.27)
			)
			(justify left)
		)
		(property "Intersheetrefs" "${INTERSHEET_REFS}"
			(at 295.2406 109.2994 0)
			(effects
				(font
					(size 1.27 1.27)
				)
				(justify left)
				(hide yes)
			)
		)
	)
	(global_label "VDD1"
		(shape input)
		(at 162.56 208.28 0)
		(fields_autoplaced yes)
		(effects
			(font
				(size 1.27 1.27)
			)
			(justify left)
		)
		(property "Intersheetrefs" "${INTERSHEET_REFS}"
			(at 5.08 0 0)
			(effects
				(font
					(size 1.27 1.27)
				)
				(hide yes)
			)
		)
	)
	(global_label "DQ_S0_TA"
		(shape input)
		(at 225.425 154.94 180)
		(fields_autoplaced yes)
		(effects
			(font
				(size 1.27 1.27)
			)
			(justify right)
		)
		(property "Intersheetrefs" "${INTERSHEET_REFS}"
			(at 214.0831 154.94 0)
			(effects
				(font
					(size 1.27 1.27)
				)
				(justify right)
				(hide yes)
			)
		)
	)
	(global_label "ODT_CA_A"
		(shape input)
		(at 286.385 142.24 0)
		(fields_autoplaced yes)
		(effects
			(font
				(size 1.27 1.27)
			)
			(justify left)
		)
		(property "Intersheetrefs" "${INTERSHEET_REFS}"
			(at 297.6597 142.1606 0)
			(effects
				(font
					(size 1.27 1.27)
				)
				(justify left)
				(hide yes)
			)
		)
	)
	(global_label "CKE0_A"
		(shape input)
		(at 286.385 147.32 0)
		(fields_autoplaced yes)
		(effects
			(font
				(size 1.27 1.27)
			)
			(justify left)
		)
		(property "Intersheetrefs" "${INTERSHEET_REFS}"
			(at 2.54 0 0)
			(effects
				(font
					(size 1.27 1.27)
				)
				(hide yes)
			)
		)
	)
	(global_label "DQ12_A"
		(shape input)
		(at 225.425 134.62 180)
		(fields_autoplaced yes)
		(effects
			(font
				(size 1.27 1.27)
			)
			(justify right)
		)
		(property "Intersheetrefs" "${INTERSHEET_REFS}"
			(at 216.0183 134.62 0)
			(effects
				(font
					(size 1.27 1.27)
				)
				(justify right)
				(hide yes)
			)
		)
	)
	(global_label "DMI_1A"
		(shape input)
		(at 225.425 116.84 180)
		(fields_autoplaced yes)
		(effects
			(font
				(size 1.27 1.27)
			)
			(justify right)
		)
		(property "Intersheetrefs" "${INTERSHEET_REFS}"
			(at 216.5021 116.84 0)
			(effects
				(font
					(size 1.27 1.27)
				)
				(justify right)
				(hide yes)
			)
		)
	)
	(global_label "DQ15_A"
		(shape input)
		(at 225.425 127 180)
		(fields_autoplaced yes)
		(effects
			(font
				(size 1.27 1.27)
			)
			(justify right)
		)
		(property "Intersheetrefs" "${INTERSHEET_REFS}"
			(at 216.0183 127 0)
			(effects
				(font
					(size 1.27 1.27)
				)
				(justify right)
				(hide yes)
			)
		)
	)
	(global_label "DQ10_A"
		(shape input)
		(at 225.425 109.22 180)
		(fields_autoplaced yes)
		(effects
			(font
				(size 1.27 1.27)
			)
			(justify right)
		)
		(property "Intersheetrefs" "${INTERSHEET_REFS}"
			(at 216.0183 109.22 0)
			(effects
				(font
					(size 1.27 1.27)
				)
				(justify right)
				(hide yes)
			)
		)
	)
	(global_label "DQ05_A"
		(shape input)
		(at 225.425 139.7 180)
		(fields_autoplaced yes)
		(effects
			(font
				(size 1.27 1.27)
			)
			(justify right)
		)
		(property "Intersheetrefs" "${INTERSHEET_REFS}"
			(at 216.0183 139.7 0)
			(effects
				(font
					(size 1.27 1.27)
				)
				(justify right)
				(hide yes)
			)
		)
	)
	(global_label "CA2_A"
		(shape input)
		(at 286.385 104.14 0)
		(fields_autoplaced yes)
		(effects
			(font
				(size 1.27 1.27)
			)
			(justify left)
		)
		(property "Intersheetrefs" "${INTERSHEET_REFS}"
			(at 2.54 0 0)
			(effects
				(font
					(size 1.27 1.27)
				)
				(hide yes)
			)
		)
	)
	(global_label "DQ_S1_TA"
		(shape input)
		(at 225.425 121.92 180)
		(fields_autoplaced yes)
		(effects
			(font
				(size 1.27 1.27)
			)
			(justify right)
		)
		(property "Intersheetrefs" "${INTERSHEET_REFS}"
			(at 214.0831 121.92 0)
			(effects
				(font
					(size 1.27 1.27)
				)
				(justify right)
				(hide yes)
			)
		)
	)
	(global_label "VDDQ"
		(shape input)
		(at 279.4 210.82 0)
		(fields_autoplaced yes)
		(effects
			(font
				(size 1.27 1.27)
			)
			(justify left)
		)
		(property "Intersheetrefs" "${INTERSHEET_REFS}"
			(at 2.54 0 0)
			(effects
				(font
					(size 1.27 1.27)
				)
				(hide yes)
			)
		)
	)
	(symbol
		(lib_id "antmicropower:GND")
		(at 149.225 231.775 0)
		(unit 1)
		(exclude_from_sim no)
		(in_bom yes)
		(on_board yes)
		(dnp no)
		(property "Reference" "#PWR0101"
			(at 149.225 238.125 0)
			(effects
				(font
					(size 1.27 1.27)
				)
				(hide yes)
			)
		)
		(property "Value" "GND"
			(at 149.352 236.1692 0)
			(effects
				(font
					(size 1.27 1.27)
				)
			)
		)
		(property "Footprint" ""
			(at 149.225 231.775 0)
			(effects
				(font
					(size 1.27 1.27)
				)
				(hide yes)
			)
		)
		(property "Datasheet" ""
			(at 149.225 231.775 0)
			(effects
				(font
					(size 1.27 1.27)
				)
				(hide yes)
			)
		)
		(property "Description" ""
			(at 149.225 231.775 0)
			(effects
				(font
					(size 1.27 1.27)
				)
			)
		)
		(pin "1"
		)
		(instances
			(project "lpddr4-testbed"
				(path ""
					(reference "#PWR0101")
					(unit 1)
				)
			)
		)
	)
	(symbol
		(lib_id "antmicropower:GND")
		(at 117.475 231.775 0)
		(unit 1)
		(exclude_from_sim no)
		(in_bom yes)
		(on_board yes)
		(dnp no)
		(property "Reference" "#PWR0103"
			(at 117.475 238.125 0)
			(effects
				(font
					(size 1.27 1.27)
				)
				(hide yes)
			)
		)
		(property "Value" "GND"
			(at 117.602 236.1692 0)
			(effects
				(font
					(size 1.27 1.27)
				)
			)
		)
		(property "Footprint" ""
			(at 117.475 231.775 0)
			(effects
				(font
					(size 1.27 1.27)
				)
				(hide yes)
			)
		)
		(property "Datasheet" ""
			(at 117.475 231.775 0)
			(effects
				(font
					(size 1.27 1.27)
				)
				(hide yes)
			)
		)
		(property "Description" ""
			(at 117.475 231.775 0)
			(effects
				(font
					(size 1.27 1.27)
				)
			)
		)
		(pin "1"
		)
		(instances
			(project "lpddr4-testbed"
				(path ""
					(reference "#PWR0103")
					(unit 1)
				)
			)
		)
	)
	(symbol
		(lib_id "antmicropower:GND")
		(at 239.395 231.775 0)
		(unit 1)
		(exclude_from_sim no)
		(in_bom yes)
		(on_board yes)
		(dnp no)
		(property "Reference" "#PWR0102"
			(at 239.395 238.125 0)
			(effects
				(font
					(size 1.27 1.27)
				)
				(hide yes)
			)
		)
		(property "Value" "GND"
			(at 239.522 236.1692 0)
			(effects
				(font
					(size 1.27 1.27)
				)
			)
		)
		(property "Footprint" ""
			(at 239.395 231.775 0)
			(effects
				(font
					(size 1.27 1.27)
				)
				(hide yes)
			)
		)
		(property "Datasheet" ""
			(at 239.395 231.775 0)
			(effects
				(font
					(size 1.27 1.27)
				)
				(hide yes)
			)
		)
		(property "Description" ""
			(at 239.395 231.775 0)
			(effects
				(font
					(size 1.27 1.27)
				)
			)
		)
		(pin "1"
		)
		(instances
			(project "lpddr4-testbed"
				(path ""
					(reference "#PWR0102")
					(unit 1)
				)
			)
		)
	)
	(symbol
		(lib_id "antmicropower:GND")
		(at 270.51 231.775 0)
		(unit 1)
		(exclude_from_sim no)
		(in_bom yes)
		(on_board yes)
		(dnp no)
		(property "Reference" "#PWR0104"
			(at 270.51 238.125 0)
			(effects
				(font
					(size 1.27 1.27)
				)
				(hide yes)
			)
		)
		(property "Value" "GND"
			(at 270.637 236.1692 0)
			(effects
				(font
					(size 1.27 1.27)
				)
			)
		)
		(property "Footprint" ""
			(at 270.51 231.775 0)
			(effects
				(font
					(size 1.27 1.27)
				)
				(hide yes)
			)
		)
		(property "Datasheet" ""
			(at 270.51 231.775 0)
			(effects
				(font
					(size 1.27 1.27)
				)
				(hide yes)
			)
		)
		(property "Description" ""
			(at 270.51 231.775 0)
			(effects
				(font
					(size 1.27 1.27)
				)
			)
		)
		(pin "1"
		)
		(instances
			(project "lpddr4-testbed"
				(path ""
					(reference "#PWR0104")
					(unit 1)
				)
			)
		)
	)
	(symbol
		(lib_id "lpddr4-testbed:Edge_Conn_Bus_DDR4")
		(at 121.92 63.5 0)
		(unit 1)
		(exclude_from_sim no)
		(in_bom no)
		(on_board yes)
		(dnp no)
		(fields_autoplaced yes)
		(property "Reference" "J1"
			(at 133.35 55.88 0)
			(effects
				(font
					(size 1.27 1.27)
					(thickness 0.15)
				)
			)
		)
		(property "Value" "Bus_DDR4_Edge_Conn"
			(at 133.35 58.42 0)
			(effects
				(font
					(size 1.27 1.27)
					(thickness 0.15)
				)
			)
		)
		(property "Footprint" "lpddr4-testbed-footprints:Edge_Conn_Bus_DDR4"
			(at 158.75 68.58 0)
			(effects
				(font
					(size 1.27 1.27)
					(thickness 0.15)
				)
				(justify left bottom)
				(hide yes)
			)
		)
		(property "Datasheet" "https://www.te.com/commerce/DocumentDelivery/DDEController?Action=showdoc&DocId=Customer+Drawing%7F2309413%7F6%7Fpdf%7FEnglish%7FENG_CD_2309413_6.pdf%7F2309413-1"
			(at 158.75 76.2 0)
			(effects
				(font
					(size 1.27 1.27)
					(thickness 0.15)
				)
				(justify left bottom)
				(hide yes)
			)
		)
		(property "Description" ""
			(at 121.92 63.5 0)
			(effects
				(font
					(size 1.27 1.27)
				)
			)
		)
		(property "MPN" ""
			(at 158.75 69.85 0)
			(effects
				(font
					(size 1.27 1.27)
				)
				(justify left)
				(hide yes)
			)
		)
		(property "Manufacturer" ""
			(at 158.75 72.39 0)
			(effects
				(font
					(size 1.27 1.27)
				)
				(justify left)
				(hide yes)
			)
		)
		(property "Author" "Antmicro"
			(at 158.75 78.74 0)
			(effects
				(font
					(size 1.27 1.27)
					(thickness 0.15)
				)
				(justify left bottom)
				(hide yes)
			)
		)
		(property "License" "Apache-2.0"
			(at 158.75 81.28 0)
			(effects
				(font
					(size 1.27 1.27)
					(thickness 0.15)
				)
				(justify left bottom)
				(hide yes)
			)
		)
		(pin "1"
		)
		(pin "10"
		)
		(pin "100"
		)
		(pin "101"
		)
		(pin "102"
		)
		(pin "103"
		)
		(pin "104"
		)
		(pin "105"
		)
		(pin "106"
		)
		(pin "107"
		)
		(pin "108"
		)
		(pin "109"
		)
		(pin "11"
		)
		(pin "110"
		)
		(pin "111"
		)
		(pin "112"
		)
		(pin "113"
		)
		(pin "114"
		)
		(pin "115"
		)
		(pin "116"
		)
		(pin "117"
		)
		(pin "118"
		)
		(pin "119"
		)
		(pin "12"
		)
		(pin "120"
		)
		(pin "121"
		)
		(pin "122"
		)
		(pin "123"
		)
		(pin "124"
		)
		(pin "125"
		)
		(pin "126"
		)
		(pin "127"
		)
		(pin "128"
		)
		(pin "129"
		)
		(pin "13"
		)
		(pin "130"
		)
		(pin "14"
		)
		(pin "15"
		)
		(pin "16"
		)
		(pin "17"
		)
		(pin "18"
		)
		(pin "19"
		)
		(pin "2"
		)
		(pin "20"
		)
		(pin "21"
		)
		(pin "22"
		)
		(pin "23"
		)
		(pin "24"
		)
		(pin "25"
		)
		(pin "26"
		)
		(pin "27"
		)
		(pin "28"
		)
		(pin "29"
		)
		(pin "3"
		)
		(pin "30"
		)
		(pin "31"
		)
		(pin "32"
		)
		(pin "33"
		)
		(pin "34"
		)
		(pin "35"
		)
		(pin "36"
		)
		(pin "37"
		)
		(pin "38"
		)
		(pin "39"
		)
		(pin "4"
		)
		(pin "40"
		)
		(pin "41"
		)
		(pin "42"
		)
		(pin "43"
		)
		(pin "44"
		)
		(pin "45"
		)
		(pin "46"
		)
		(pin "47"
		)
		(pin "48"
		)
		(pin "49"
		)
		(pin "5"
		)
		(pin "50"
		)
		(pin "51"
		)
		(pin "52"
		)
		(pin "53"
		)
		(pin "54"
		)
		(pin "55"
		)
		(pin "56"
		)
		(pin "57"
		)
		(pin "58"
		)
		(pin "59"
		)
		(pin "6"
		)
		(pin "60"
		)
		(pin "61"
		)
		(pin "62"
		)
		(pin "63"
		)
		(pin "64"
		)
		(pin "65"
		)
		(pin "66"
		)
		(pin "67"
		)
		(pin "68"
		)
		(pin "69"
		)
		(pin "7"
		)
		(pin "70"
		)
		(pin "71"
		)
		(pin "72"
		)
		(pin "73"
		)
		(pin "74"
		)
		(pin "75"
		)
		(pin "76"
		)
		(pin "77"
		)
		(pin "78"
		)
		(pin "79"
		)
		(pin "8"
		)
		(pin "80"
		)
		(pin "81"
		)
		(pin "82"
		)
		(pin "83"
		)
		(pin "84"
		)
		(pin "85"
		)
		(pin "86"
		)
		(pin "87"
		)
		(pin "88"
		)
		(pin "89"
		)
		(pin "9"
		)
		(pin "90"
		)
		(pin "91"
		)
		(pin "92"
		)
		(pin "93"
		)
		(pin "94"
		)
		(pin "95"
		)
		(pin "96"
		)
		(pin "97"
		)
		(pin "98"
		)
		(pin "99"
		)
		(pin "131"
		)
		(pin "132"
		)
		(pin "133"
		)
		(pin "134"
		)
		(pin "135"
		)
		(pin "136"
		)
		(pin "137"
		)
		(pin "138"
		)
		(pin "139"
		)
		(pin "140"
		)
		(pin "141"
		)
		(pin "142"
		)
		(pin "143"
		)
		(pin "144"
		)
		(pin "145"
		)
		(pin "146"
		)
		(pin "147"
		)
		(pin "148"
		)
		(pin "149"
		)
		(pin "150"
		)
		(pin "151"
		)
		(pin "152"
		)
		(pin "153"
		)
		(pin "154"
		)
		(pin "155"
		)
		(pin "156"
		)
		(pin "157"
		)
		(pin "158"
		)
		(pin "159"
		)
		(pin "160"
		)
		(pin "161"
		)
		(pin "162"
		)
		(pin "163"
		)
		(pin "164"
		)
		(pin "165"
		)
		(pin "166"
		)
		(pin "167"
		)
		(pin "168"
		)
		(pin "169"
		)
		(pin "170"
		)
		(pin "171"
		)
		(pin "172"
		)
		(pin "173"
		)
		(pin "174"
		)
		(pin "175"
		)
		(pin "176"
		)
		(pin "177"
		)
		(pin "178"
		)
		(pin "179"
		)
		(pin "180"
		)
		(pin "181"
		)
		(pin "182"
		)
		(pin "183"
		)
		(pin "184"
		)
		(pin "185"
		)
		(pin "186"
		)
		(pin "187"
		)
		(pin "188"
		)
		(pin "189"
		)
		(pin "190"
		)
		(pin "191"
		)
		(pin "192"
		)
		(pin "193"
		)
		(pin "194"
		)
		(pin "195"
		)
		(pin "196"
		)
		(pin "197"
		)
		(pin "198"
		)
		(pin "199"
		)
		(pin "200"
		)
		(pin "201"
		)
		(pin "202"
		)
		(pin "203"
		)
		(pin "204"
		)
		(pin "205"
		)
		(pin "206"
		)
		(pin "207"
		)
		(pin "208"
		)
		(pin "209"
		)
		(pin "210"
		)
		(pin "211"
		)
		(pin "212"
		)
		(pin "213"
		)
		(pin "214"
		)
		(pin "215"
		)
		(pin "216"
		)
		(pin "217"
		)
		(pin "218"
		)
		(pin "219"
		)
		(pin "220"
		)
		(pin "221"
		)
		(pin "222"
		)
		(pin "223"
		)
		(pin "224"
		)
		(pin "225"
		)
		(pin "226"
		)
		(pin "227"
		)
		(pin "228"
		)
		(pin "229"
		)
		(pin "230"
		)
		(pin "231"
		)
		(pin "232"
		)
		(pin "233"
		)
		(pin "234"
		)
		(pin "235"
		)
		(pin "236"
		)
		(pin "237"
		)
		(pin "238"
		)
		(pin "239"
		)
		(pin "240"
		)
		(pin "241"
		)
		(pin "242"
		)
		(pin "243"
		)
		(pin "244"
		)
		(pin "245"
		)
		(pin "246"
		)
		(pin "247"
		)
		(pin "248"
		)
		(pin "249"
		)
		(pin "250"
		)
		(pin "251"
		)
		(pin "252"
		)
		(pin "253"
		)
		(pin "254"
		)
		(pin "255"
		)
		(pin "256"
		)
		(pin "257"
		)
		(pin "258"
		)
		(pin "259"
		)
		(pin "260"
		)
		(instances
			(project "lpddr4-testbed"
				(path ""
					(reference "J1")
					(unit 1)
				)
			)
		)
	)
	(symbol
		(lib_id "antmicropower:PWR_FLAG")
		(at 107.95 179.705 0)
		(unit 1)
		(exclude_from_sim no)
		(in_bom yes)
		(on_board yes)
		(dnp no)
		(property "Reference" "#FLG0104"
			(at 107.95 177.8 0)
			(effects
				(font
					(size 1.27 1.27)
				)
				(hide yes)
			)
		)
		(property "Value" "PWR_FLAG"
			(at 107.95 175.895 0)
			(effects
				(font
					(size 1.27 1.27)
				)
			)
		)
		(property "Footprint" ""
			(at 107.95 179.705 0)
			(effects
				(font
					(size 1.27 1.27)
				)
				(hide yes)
			)
		)
		(property "Datasheet" ""
			(at 107.95 179.705 0)
			(effects
				(font
					(size 1.27 1.27)
				)
				(hide yes)
			)
		)
		(property "Description" ""
			(at 107.95 179.705 0)
			(effects
				(font
					(size 1.27 1.27)
				)
			)
		)
		(pin "1"
		)
		(instances
			(project "lpddr4-testbed"
				(path ""
					(reference "#FLG0104")
					(unit 1)
				)
			)
		)
	)
	(symbol
		(lib_id "antmicropower:PWR_FLAG")
		(at 159.385 207.645 0)
		(unit 1)
		(exclude_from_sim no)
		(in_bom yes)
		(on_board yes)
		(dnp no)
		(property "Reference" "#FLG0102"
			(at 159.385 205.74 0)
			(effects
				(font
					(size 1.27 1.27)
				)
				(hide yes)
			)
		)
		(property "Value" "PWR_FLAG"
			(at 159.385 203.835 0)
			(effects
				(font
					(size 1.27 1.27)
				)
			)
		)
		(property "Footprint" ""
			(at 159.385 207.645 0)
			(effects
				(font
					(size 1.27 1.27)
				)
				(hide yes)
			)
		)
		(property "Datasheet" ""
			(at 159.385 207.645 0)
			(effects
				(font
					(size 1.27 1.27)
				)
				(hide yes)
			)
		)
		(property "Description" ""
			(at 159.385 207.645 0)
			(effects
				(font
					(size 1.27 1.27)
				)
			)
		)
		(pin "1"
		)
		(instances
			(project "lpddr4-testbed"
				(path ""
					(reference "#FLG0102")
					(unit 1)
				)
			)
		)
	)
	(symbol
		(lib_id "antmicropower:PWR_FLAG")
		(at 149.225 62.865 0)
		(unit 1)
		(exclude_from_sim no)
		(in_bom yes)
		(on_board yes)
		(dnp no)
		(property "Reference" "#FLG0103"
			(at 149.225 60.96 0)
			(effects
				(font
					(size 1.27 1.27)
				)
				(hide yes)
			)
		)
		(property "Value" "PWR_FLAG"
			(at 149.225 59.055 0)
			(effects
				(font
					(size 1.27 1.27)
				)
			)
		)
		(property "Footprint" ""
			(at 149.225 62.865 0)
			(effects
				(font
					(size 1.27 1.27)
				)
				(hide yes)
			)
		)
		(property "Datasheet" ""
			(at 149.225 62.865 0)
			(effects
				(font
					(size 1.27 1.27)
				)
				(hide yes)
			)
		)
		(property "Description" ""
			(at 149.225 62.865 0)
			(effects
				(font
					(size 1.27 1.27)
				)
			)
		)
		(pin "1"
		)
		(instances
			(project "lpddr4-testbed"
				(path ""
					(reference "#FLG0103")
					(unit 1)
				)
			)
		)
	)
	(symbol
		(lib_id "antmicropower:PWR_FLAG")
		(at 159.385 220.345 0)
		(unit 1)
		(exclude_from_sim no)
		(in_bom yes)
		(on_board yes)
		(dnp no)
		(property "Reference" "#FLG0101"
			(at 159.385 218.44 0)
			(effects
				(font
					(size 1.27 1.27)
				)
				(hide yes)
			)
		)
		(property "Value" "PWR_FLAG"
			(at 159.385 216.535 0)
			(effects
				(font
					(size 1.27 1.27)
				)
			)
		)
		(property "Footprint" ""
			(at 159.385 220.345 0)
			(effects
				(font
					(size 1.27 1.27)
				)
				(hide yes)
			)
		)
		(property "Datasheet" ""
			(at 159.385 220.345 0)
			(effects
				(font
					(size 1.27 1.27)
				)
				(hide yes)
			)
		)
		(property "Description" ""
			(at 159.385 220.345 0)
			(effects
				(font
					(size 1.27 1.27)
				)
			)
		)
		(pin "1"
		)
		(instances
			(project "lpddr4-testbed"
				(path ""
					(reference "#FLG0101")
					(unit 1)
				)
			)
		)
	)
	(symbol
		(lib_id "lpddr4-testbed:Edge_Conn_Bus_DDR4")
		(at 243.84 66.04 0)
		(unit 2)
		(exclude_from_sim no)
		(in_bom no)
		(on_board yes)
		(dnp no)
		(fields_autoplaced yes)
		(property "Reference" "J1"
			(at 255.27 58.42 0)
			(effects
				(font
					(size 1.27 1.27)
					(thickness 0.15)
				)
			)
		)
		(property "Value" "Bus_DDR4_Edge_Conn"
			(at 255.27 60.96 0)
			(effects
				(font
					(size 1.27 1.27)
					(thickness 0.15)
				)
			)
		)
		(property "Footprint" "lpddr4-testbed-footprints:Edge_Conn_Bus_DDR4"
			(at 280.67 71.12 0)
			(effects
				(font
					(size 1.27 1.27)
					(thickness 0.15)
				)
				(justify left bottom)
				(hide yes)
			)
		)
		(property "Datasheet" "https://www.te.com/commerce/DocumentDelivery/DDEController?Action=showdoc&DocId=Customer+Drawing%7F2309413%7F6%7Fpdf%7FEnglish%7FENG_CD_2309413_6.pdf%7F2309413-1"
			(at 280.67 78.74 0)
			(effects
				(font
					(size 1.27 1.27)
					(thickness 0.15)
				)
				(justify left bottom)
				(hide yes)
			)
		)
		(property "Description" ""
			(at 243.84 66.04 0)
			(effects
				(font
					(size 1.27 1.27)
				)
			)
		)
		(property "MPN" ""
			(at 280.67 72.39 0)
			(effects
				(font
					(size 1.27 1.27)
				)
				(justify left)
				(hide yes)
			)
		)
		(property "Manufacturer" ""
			(at 280.67 74.93 0)
			(effects
				(font
					(size 1.27 1.27)
				)
				(justify left)
				(hide yes)
			)
		)
		(property "Author" "Antmicro"
			(at 280.67 81.28 0)
			(effects
				(font
					(size 1.27 1.27)
					(thickness 0.15)
				)
				(justify left bottom)
				(hide yes)
			)
		)
		(property "License" "Apache-2.0"
			(at 280.67 83.82 0)
			(effects
				(font
					(size 1.27 1.27)
					(thickness 0.15)
				)
				(justify left bottom)
				(hide yes)
			)
		)
		(pin "1"
		)
		(pin "10"
		)
		(pin "100"
		)
		(pin "101"
		)
		(pin "102"
		)
		(pin "103"
		)
		(pin "104"
		)
		(pin "105"
		)
		(pin "106"
		)
		(pin "107"
		)
		(pin "108"
		)
		(pin "109"
		)
		(pin "11"
		)
		(pin "110"
		)
		(pin "111"
		)
		(pin "112"
		)
		(pin "113"
		)
		(pin "114"
		)
		(pin "115"
		)
		(pin "116"
		)
		(pin "117"
		)
		(pin "118"
		)
		(pin "119"
		)
		(pin "12"
		)
		(pin "120"
		)
		(pin "121"
		)
		(pin "122"
		)
		(pin "123"
		)
		(pin "124"
		)
		(pin "125"
		)
		(pin "126"
		)
		(pin "127"
		)
		(pin "128"
		)
		(pin "129"
		)
		(pin "13"
		)
		(pin "130"
		)
		(pin "14"
		)
		(pin "15"
		)
		(pin "16"
		)
		(pin "17"
		)
		(pin "18"
		)
		(pin "19"
		)
		(pin "2"
		)
		(pin "20"
		)
		(pin "21"
		)
		(pin "22"
		)
		(pin "23"
		)
		(pin "24"
		)
		(pin "25"
		)
		(pin "26"
		)
		(pin "27"
		)
		(pin "28"
		)
		(pin "29"
		)
		(pin "3"
		)
		(pin "30"
		)
		(pin "31"
		)
		(pin "32"
		)
		(pin "33"
		)
		(pin "34"
		)
		(pin "35"
		)
		(pin "36"
		)
		(pin "37"
		)
		(pin "38"
		)
		(pin "39"
		)
		(pin "4"
		)
		(pin "40"
		)
		(pin "41"
		)
		(pin "42"
		)
		(pin "43"
		)
		(pin "44"
		)
		(pin "45"
		)
		(pin "46"
		)
		(pin "47"
		)
		(pin "48"
		)
		(pin "49"
		)
		(pin "5"
		)
		(pin "50"
		)
		(pin "51"
		)
		(pin "52"
		)
		(pin "53"
		)
		(pin "54"
		)
		(pin "55"
		)
		(pin "56"
		)
		(pin "57"
		)
		(pin "58"
		)
		(pin "59"
		)
		(pin "6"
		)
		(pin "60"
		)
		(pin "61"
		)
		(pin "62"
		)
		(pin "63"
		)
		(pin "64"
		)
		(pin "65"
		)
		(pin "66"
		)
		(pin "67"
		)
		(pin "68"
		)
		(pin "69"
		)
		(pin "7"
		)
		(pin "70"
		)
		(pin "71"
		)
		(pin "72"
		)
		(pin "73"
		)
		(pin "74"
		)
		(pin "75"
		)
		(pin "76"
		)
		(pin "77"
		)
		(pin "78"
		)
		(pin "79"
		)
		(pin "8"
		)
		(pin "80"
		)
		(pin "81"
		)
		(pin "82"
		)
		(pin "83"
		)
		(pin "84"
		)
		(pin "85"
		)
		(pin "86"
		)
		(pin "87"
		)
		(pin "88"
		)
		(pin "89"
		)
		(pin "9"
		)
		(pin "90"
		)
		(pin "91"
		)
		(pin "92"
		)
		(pin "93"
		)
		(pin "94"
		)
		(pin "95"
		)
		(pin "96"
		)
		(pin "97"
		)
		(pin "98"
		)
		(pin "99"
		)
		(pin "131"
		)
		(pin "132"
		)
		(pin "133"
		)
		(pin "134"
		)
		(pin "135"
		)
		(pin "136"
		)
		(pin "137"
		)
		(pin "138"
		)
		(pin "139"
		)
		(pin "140"
		)
		(pin "141"
		)
		(pin "142"
		)
		(pin "143"
		)
		(pin "144"
		)
		(pin "145"
		)
		(pin "146"
		)
		(pin "147"
		)
		(pin "148"
		)
		(pin "149"
		)
		(pin "150"
		)
		(pin "151"
		)
		(pin "152"
		)
		(pin "153"
		)
		(pin "154"
		)
		(pin "155"
		)
		(pin "156"
		)
		(pin "157"
		)
		(pin "158"
		)
		(pin "159"
		)
		(pin "160"
		)
		(pin "161"
		)
		(pin "162"
		)
		(pin "163"
		)
		(pin "164"
		)
		(pin "165"
		)
		(pin "166"
		)
		(pin "167"
		)
		(pin "168"
		)
		(pin "169"
		)
		(pin "170"
		)
		(pin "171"
		)
		(pin "172"
		)
		(pin "173"
		)
		(pin "174"
		)
		(pin "175"
		)
		(pin "176"
		)
		(pin "177"
		)
		(pin "178"
		)
		(pin "179"
		)
		(pin "180"
		)
		(pin "181"
		)
		(pin "182"
		)
		(pin "183"
		)
		(pin "184"
		)
		(pin "185"
		)
		(pin "186"
		)
		(pin "187"
		)
		(pin "188"
		)
		(pin "189"
		)
		(pin "190"
		)
		(pin "191"
		)
		(pin "192"
		)
		(pin "193"
		)
		(pin "194"
		)
		(pin "195"
		)
		(pin "196"
		)
		(pin "197"
		)
		(pin "198"
		)
		(pin "199"
		)
		(pin "200"
		)
		(pin "201"
		)
		(pin "202"
		)
		(pin "203"
		)
		(pin "204"
		)
		(pin "205"
		)
		(pin "206"
		)
		(pin "207"
		)
		(pin "208"
		)
		(pin "209"
		)
		(pin "210"
		)
		(pin "211"
		)
		(pin "212"
		)
		(pin "213"
		)
		(pin "214"
		)
		(pin "215"
		)
		(pin "216"
		)
		(pin "217"
		)
		(pin "218"
		)
		(pin "219"
		)
		(pin "220"
		)
		(pin "221"
		)
		(pin "222"
		)
		(pin "223"
		)
		(pin "224"
		)
		(pin "225"
		)
		(pin "226"
		)
		(pin "227"
		)
		(pin "228"
		)
		(pin "229"
		)
		(pin "230"
		)
		(pin "231"
		)
		(pin "232"
		)
		(pin "233"
		)
		(pin "234"
		)
		(pin "235"
		)
		(pin "236"
		)
		(pin "237"
		)
		(pin "238"
		)
		(pin "239"
		)
		(pin "240"
		)
		(pin "241"
		)
		(pin "242"
		)
		(pin "243"
		)
		(pin "244"
		)
		(pin "245"
		)
		(pin "246"
		)
		(pin "247"
		)
		(pin "248"
		)
		(pin "249"
		)
		(pin "250"
		)
		(pin "251"
		)
		(pin "252"
		)
		(pin "253"
		)
		(pin "254"
		)
		(pin "255"
		)
		(pin "256"
		)
		(pin "257"
		)
		(pin "258"
		)
		(pin "259"
		)
		(pin "260"
		)
		(instances
			(project "lpddr4-testbed"
				(path ""
					(reference "J1")
					(unit 2)
				)
			)
		)
	)
)
